#ISCELL
  mstr_misc dns *
  *
#ISCELL
  pure_quanta quanta_title_block_c *
  *
#ISCELL
  standard offpage *
  page252_i1
#CELL
  pure_quanta q_res *
  page252_i10
#ISCELL
  standard offpage *
  page252_i100
#ISCELL
  standard offpage *
  page252_i101
#ISCELL
  standard offpage *
  page252_i102
#ISCELL
  standard offpage *
  page252_i103
#ISCELL
  standard offpage *
  page252_i104
#ISCELL
  standard offpage *
  page252_i105
#ISCELL
  standard offpage *
  page252_i106
#ISCELL
  standard offpage *
  page252_i107
#ISCELL
  standard offpage *
  page252_i108
#ISCELL
  standard offpage *
  page252_i109
#CELL
  pure_quanta q_res *
  page252_i11
#ISCELL
  standard offpage *
  page252_i110
#ISCELL
  standard offpage *
  page252_i111
#ISCELL
  standard offpage *
  page252_i112
#ISCELL
  standard offpage *
  page252_i113
#ISCELL
  logical_power universal_gnd *
  page252_i114
#ISCELL
  standard offpage *
  page252_i115
#CELL
  pure_quanta q_cap *
  page252_i116
#ISCELL
  standard offpage *
  page252_i117
#ISCELL
  standard offpage *
  page252_i118
#ISCELL
  standard offpage *
  page252_i119
#ISCELL
  logical_power vcc15 *
  page252_i12
#ISCELL
  logical_power universal_gnd *
  page252_i120
#CELL
  pure_quanta q_res *
  page252_i121
#ISCELL
  standard offpage *
  page252_i122
#CELL
  pure_quanta q_res *
  page252_i123
#CELL
  pure_quanta q_res *
  page252_i124
#CELL
  pure_quanta q_res *
  page252_i125
#ISCELL
  logical_power universal_gnd *
  page252_i126
#CELL
  pure_quanta q_cap *
  page252_i127
#CELL
  pure_quanta q_cap *
  page252_i128
#ISCELL
  logical_power vcc15 *
  page252_i129
#ISCELL
  logical_power vcc15 *
  page252_i13
#ISCELL
  logical_power universal_gnd *
  page252_i130
#ISCELL
  standard offpage *
  page252_i131
#ISCELL
  logical_power universal_gnd *
  page252_i132
#CELL
  pure_quanta q_res *
  page252_i133
#ISCELL
  logical_power vcc15 *
  page252_i134
#CELL
  pure_quanta q_cap *
  page252_i136
#ISCELL
  standard offpage *
  page252_i14
#CELL
  pure_quanta q_res *
  page252_i15
#ISCELL
  logical_power vcc15 *
  page252_i16
#CELL
  pure_quanta q_res *
  page252_i17
#ISCELL
  standard offpage *
  page252_i18
#CELL
  pure_quanta q_res *
  page252_i19
#ISCELL
  standard offpage *
  page252_i2
#CELL
  pure_quanta q_res *
  page252_i20
#ISCELL
  logical_power universal_gnd *
  page252_i21
#ISCELL
  logical_power vcc15 *
  page252_i22
#CELL
  pure_quanta q_res *
  page252_i23
#CELL
  pure_quanta q_short *
  page252_i24
#CELL
  pure_quanta q_res *
  page252_i25
#CELL
  pure_quanta q_res *
  page252_i26
#ISCELL
  logical_power vcc15 *
  page252_i27
#ISCELL
  logical_power universal_gnd *
  page252_i28
#ISCELL
  standard offpage *
  page252_i29
#ISCELL
  standard offpage *
  page252_i3
#ISCELL
  standard offpage *
  page252_i30
#ISCELL
  standard offpage *
  page252_i31
#CELL
  pure_quanta conn3_210hp1030br1 *
  page252_i32
#ISCELL
  standard offpage *
  page252_i33
#ISCELL
  logical_power universal_gnd *
  page252_i34
#ISCELL
  standard offpage *
  page252_i35
#ISCELL
  standard offpage *
  page252_i36
#CELL
  pure_quanta q_short *
  page252_i37
#CELL
  pure_quanta q_res *
  page252_i38
#ISCELL
  logical_power vcc15 *
  page252_i39
#ISCELL
  standard offpage *
  page252_i4
#CELL
  pure_quanta q_res *
  page252_i40
#CELL
  pure_quanta q_res *
  page252_i41
#CELL
  pure_quanta q_res *
  page252_i42
#CELL
  pure_quanta q_res *
  page252_i43
#CELL
  pure_quanta q_res *
  page252_i44
#ISCELL
  standard offpage *
  page252_i45
#ISCELL
  standard offpage *
  page252_i46
#ISCELL
  logical_power vcc15 *
  page252_i47
#CELL
  pure_quanta q_res *
  page252_i48
#CELL
  pure_quanta q_res *
  page252_i49
#CELL
  pure_quanta q_res *
  page252_i5
#CELL
  pure_quanta q_res *
  page252_i50
#CELL
  pure_quanta q_res *
  page252_i51
#ISCELL
  logical_power universal_gnd *
  page252_i52
#CELL
  pure_quanta q_cap *
  page252_i53
#CELL
  pure_quanta q_res *
  page252_i54
#CELL
  pure_quanta q_res *
  page252_i55
#CELL
  pure_quanta q_res *
  page252_i56
#CELL
  pure_quanta q_cap *
  page252_i57
#CELL
  pure_quanta q_cap *
  page252_i58
#ISCELL
  logical_power universal_gnd *
  page252_i59
#ISCELL
  standard offpage *
  page252_i6
#CELL
  pure_quanta q_res *
  page252_i60
#CELL
  pure_quanta q_cap *
  page252_i61
#ISCELL
  logical_power universal_gnd *
  page252_i62
#CELL
  pure_quanta raa229126gnpha0 *
  page252_i63
#ISCELL
  logical_power universal_gnd *
  page252_i64
#ISCELL
  logical_power universal_gnd *
  page252_i65
#CELL
  pure_quanta q_res *
  page252_i66
#CELL
  pure_quanta q_cap *
  page252_i67
#CELL
  pure_quanta q_res *
  page252_i68
#ISCELL
  logical_power universal_gnd *
  page252_i69
#ISCELL
  standard offpage *
  page252_i7
#CELL
  pure_quanta q_cap *
  page252_i70
#ISCELL
  logical_power universal_gnd *
  page252_i71
#CELL
  pure_quanta q_res *
  page252_i72
#CELL
  pure_quanta q_res *
  page252_i73
#CELL
  pure_quanta q_res *
  page252_i74
#ISCELL
  logical_power universal_gnd *
  page252_i75
#ISCELL
  logical_power universal_gnd *
  page252_i76
#CELL
  pure_quanta q_res *
  page252_i77
#CELL
  pure_quanta q_res *
  page252_i78
#CELL
  pure_quanta q_cap *
  page252_i79
#CELL
  pure_quanta q_res *
  page252_i8
#CELL
  pure_quanta q_res *
  page252_i80
#ISCELL
  logical_power vcc15 *
  page252_i81
#CELL
  pure_quanta q_cap *
  page252_i82
#ISCELL
  logical_power universal_gnd *
  page252_i83
#CELL
  pure_quanta q_cap *
  page252_i84
#ISCELL
  logical_power universal_gnd *
  page252_i85
#CELL
  pure_quanta q_cap *
  page252_i86
#CELL
  pure_quanta q_cap *
  page252_i87
#CELL
  pure_quanta q_cap *
  page252_i88
#CELL
  pure_quanta q_cap *
  page252_i89
#ISCELL
  logical_power universal_gnd *
  page252_i9
#ISCELL
  standard offpage *
  page252_i90
#ISCELL
  standard offpage *
  page252_i91
#ISCELL
  standard offpage *
  page252_i92
#ISCELL
  standard offpage *
  page252_i93
#ISCELL
  standard offpage *
  page252_i94
#ISCELL
  standard offpage *
  page252_i95
#ISCELL
  standard offpage *
  page252_i96
#ISCELL
  standard offpage *
  page252_i97
#ISCELL
  standard offpage *
  page252_i98
#ISCELL
  standard offpage *
  page252_i99
